(kicad_pcb
	(version 20241229)
	(generator "pcbnew")
	(generator_version "9.0")
	(general
		(thickness 1.711)
		(legacy_teardrops no)
	)
	(paper "A4")
	(title_block
		(title "Antmicro Baseboard for Jetson AGX Thor")
		(date "2026-02-18")
		(rev "1.1.0")
		(company "Antmicro Ltd")
		(comment 1 "www.antmicro.com")
		(comment 9 "footprint 710 of 1170 (J18), pads 189-279 of 564")
	)
	(layers
		(0 "F.Cu" signal)
		(4 "In1.Cu" signal)
		(6 "In2.Cu" signal)
		(8 "In3.Cu" signal)
		(10 "In4.Cu" jumper)
		(12 "In5.Cu" signal)
		(14 "In6.Cu" signal)
		(16 "In7.Cu" signal)
		(18 "In8.Cu" signal)
		(2 "B.Cu" signal)
		(9 "F.Adhes" user "F.Adhesive")
		(11 "B.Adhes" user "B.Adhesive")
		(13 "F.Paste" user)
		(15 "B.Paste" user)
		(5 "F.SilkS" user "F.Silkscreen")
		(7 "B.SilkS" user "B.Silkscreen")
		(1 "F.Mask" user)
		(3 "B.Mask" user)
		(17 "Dwgs.User" user "User.Drawings")
		(19 "Cmts.User" user "User.Comments")
		(21 "Eco1.User" user "User.Eco1")
		(23 "Eco2.User" user "User.Eco2")
		(25 "Edge.Cuts" user)
		(27 "Margin" user)
		(31 "F.CrtYd" user "F.Courtyard")
		(29 "B.CrtYd" user "B.Courtyard")
		(35 "F.Fab" user)
		(33 "B.Fab" user)
	)
	(footprint "antmicro-footprints:ASP-208571-01_mounting_holes"
		(locked yes)
		(layer "B.Cu")
		(at 77.680532 103.71 90)
		(property "Reference" "J18"
			(at -25.89 11.119468 270)
			(layer "B.SilkS")
			(effects
				(font
					(size 0.7 0.7)
					(thickness 0.15)
				)
				(justify left bottom mirror)
			)
		)
		(property "Value" "ASP-208571-01_mounting_holes"
			(at -15.05 -10.885 270)
			(layer "B.Fab")
			(effects
				(font
					(size 0.7 0.7)
					(thickness 0.15)
				)
				(justify left bottom mirror)
			)
		)
		(property "Datasheet" "https://suddendocs.samtec.com/prints/asp-208571-01-mkt.pdf"
			(at 0 0 270)
			(layer "B.Fab")
			(hide yes)
			(effects
				(font
					(size 1.27 1.27)
					(thickness 0.15)
				)
				(justify mirror)
			)
		)
		(property "Description" "FMC connector"
			(at 0 0 270)
			(layer "B.Fab")
			(hide yes)
			(effects
				(font
					(size 1.27 1.27)
					(thickness 0.15)
				)
				(justify mirror)
			)
		)
		(property "MPN" "ASP-208571-01"
			(at 0 0 90)
			(unlocked yes)
			(layer "B.Fab")
			(hide yes)
			(effects
				(font
					(size 1 1)
					(thickness 0.15)
				)
				(justify mirror)
			)
		)
		(property "Manufacturer" "Samtec"
			(at 0 0 90)
			(unlocked yes)
			(layer "B.Fab")
			(hide yes)
			(effects
				(font
					(size 1 1)
					(thickness 0.15)
				)
				(justify mirror)
			)
		)
		(property "Author" "Antmicro"
			(at 0 0 90)
			(unlocked yes)
			(layer "B.Fab")
			(hide yes)
			(effects
				(font
					(size 1 1)
					(thickness 0.15)
				)
				(justify mirror)
			)
		)
		(property "License" "Apache-2.0"
			(at 0 0 90)
			(unlocked yes)
			(layer "B.Fab")
			(hide yes)
			(effects
				(font
					(size 1 1)
					(thickness 0.15)
				)
				(justify mirror)
			)
		)
		(sheetname "/Expansion connector/")
		(sheetfile "expansion_connector.kicad_sch")
		(attr smd)
		(pad "E25" smd circle
			(at -5.715 0.635 90)
			(size 0.64 0.64)
			(layers "B.Cu" "B.Mask")
			(net 290 "unconnected-(J18-PadE25)")
			(pinfunction "E25")
			(pintype "passive+no_connect")
		)
		(pad "E26" smd circle
			(at -6.985 0.635 90)
			(size 0.64 0.64)
			(layers "B.Cu" "B.Mask")
			(net 1 "GND")
			(pinfunction "E26")
			(pintype "passive")
		)
		(pad "E27" smd circle
			(at -8.255 0.635 90)
			(size 0.64 0.64)
			(layers "B.Cu" "B.Mask")
			(net 845 "unconnected-(J18-PadE27)")
			(pinfunction "E27")
			(pintype "passive+no_connect")
		)
		(pad "E28" smd circle
			(at -9.525 0.635 90)
			(size 0.64 0.64)
			(layers "B.Cu" "B.Mask")
			(net 457 "unconnected-(J18-PadE28)")
			(pinfunction "E28")
			(pintype "passive+no_connect")
		)
		(pad "E29" smd circle
			(at -10.795 0.635 90)
			(size 0.64 0.64)
			(layers "B.Cu" "B.Mask")
			(net 1 "GND")
			(pinfunction "E29")
			(pintype "passive")
		)
		(pad "E30" smd circle
			(at -12.065 0.635 90)
			(size 0.64 0.64)
			(layers "B.Cu" "B.Mask")
			(net 847 "unconnected-(J18-PadE30)")
			(pinfunction "E30")
			(pintype "passive+no_connect")
		)
		(pad "E31" smd circle
			(at -13.335 0.635 90)
			(size 0.64 0.64)
			(layers "B.Cu" "B.Mask")
			(net 855 "unconnected-(J18-PadE31)")
			(pinfunction "E31")
			(pintype "passive+no_connect")
		)
		(pad "E32" smd circle
			(at -14.605 0.635 90)
			(size 0.64 0.64)
			(layers "B.Cu" "B.Mask")
			(net 1 "GND")
			(pinfunction "E32")
			(pintype "passive")
		)
		(pad "E33" smd circle
			(at -15.875 0.635 90)
			(size 0.64 0.64)
			(layers "B.Cu" "B.Mask")
			(net 312 "unconnected-(J18-PadE33)")
			(pinfunction "E33")
			(pintype "passive+no_connect")
		)
		(pad "E34" smd circle
			(at -17.145 0.635 90)
			(size 0.64 0.64)
			(layers "B.Cu" "B.Mask")
			(net 477 "unconnected-(J18-PadE34)")
			(pinfunction "E34")
			(pintype "passive+no_connect")
		)
		(pad "E35" smd circle
			(at -18.415 0.635 90)
			(size 0.64 0.64)
			(layers "B.Cu" "B.Mask")
			(net 1 "GND")
			(pinfunction "E35")
			(pintype "passive")
		)
		(pad "E36" smd circle
			(at -19.685 0.635 90)
			(size 0.64 0.64)
			(layers "B.Cu" "B.Mask")
			(net 358 "unconnected-(J18-PadE36)")
			(pinfunction "E36")
			(pintype "passive+no_connect")
		)
		(pad "E37" smd circle
			(at -20.955 0.635 90)
			(size 0.64 0.64)
			(layers "B.Cu" "B.Mask")
			(net 447 "unconnected-(J18-PadE37)")
			(pinfunction "E37")
			(pintype "passive+no_connect")
		)
		(pad "E38" smd circle
			(at -22.225 0.635 90)
			(size 0.64 0.64)
			(layers "B.Cu" "B.Mask")
			(net 1 "GND")
			(pinfunction "E38")
			(pintype "passive")
		)
		(pad "E39" smd circle
			(at -23.495 0.635 90)
			(size 0.64 0.64)
			(layers "B.Cu" "B.Mask")
			(net 295 "/Expansion connector/+V_{ADJ}")
			(pinfunction "E39")
			(pintype "passive")
		)
		(pad "E40" smd circle
			(at -24.765 0.635 90)
			(size 0.64 0.64)
			(layers "B.Cu" "B.Mask")
			(net 1 "GND")
			(pinfunction "E40")
			(pintype "passive")
		)
		(pad "F01" smd circle
			(at 24.765 -0.635 90)
			(size 0.64 0.64)
			(layers "B.Cu" "B.Mask")
			(net 330 "/Expansion connector/FMC_PG_M2C")
			(pinfunction "F01")
			(pintype "passive")
		)
		(pad "F02" smd circle
			(at 23.495 -0.635 90)
			(size 0.64 0.64)
			(layers "B.Cu" "B.Mask")
			(net 1 "GND")
			(pinfunction "F02")
			(pintype "passive")
		)
		(pad "F03" smd circle
			(at 22.225 -0.635 90)
			(size 0.64 0.64)
			(layers "B.Cu" "B.Mask")
			(net 1 "GND")
			(pinfunction "F03")
			(pintype "passive")
		)
		(pad "F04" smd circle
			(at 20.955 -0.635 90)
			(size 0.64 0.64)
			(layers "B.Cu" "B.Mask")
			(net 441 "unconnected-(J18-PadF04)")
			(pinfunction "F04")
			(pintype "passive+no_connect")
		)
		(pad "F05" smd circle
			(at 19.685 -0.635 90)
			(size 0.64 0.64)
			(layers "B.Cu" "B.Mask")
			(net 481 "unconnected-(J18-PadF05)")
			(pinfunction "F05")
			(pintype "passive+no_connect")
		)
		(pad "F06" smd circle
			(at 18.415 -0.635 90)
			(size 0.64 0.64)
			(layers "B.Cu" "B.Mask")
			(net 1 "GND")
			(pinfunction "F06")
			(pintype "passive")
		)
		(pad "F07" smd circle
			(at 17.145 -0.635 90)
			(size 0.64 0.64)
			(layers "B.Cu" "B.Mask")
			(net 455 "unconnected-(J18-PadF07)")
			(pinfunction "F07")
			(pintype "passive+no_connect")
		)
		(pad "F08" smd circle
			(at 15.875 -0.635 90)
			(size 0.64 0.64)
			(layers "B.Cu" "B.Mask")
			(net 316 "unconnected-(J18-PadF08)")
			(pinfunction "F08")
			(pintype "passive+no_connect")
		)
		(pad "F09" smd circle
			(at 14.605 -0.635 90)
			(size 0.64 0.64)
			(layers "B.Cu" "B.Mask")
			(net 1 "GND")
			(pinfunction "F09")
			(pintype "passive")
		)
		(pad "F10" smd circle
			(at 13.335 -0.635 90)
			(size 0.64 0.64)
			(layers "B.Cu" "B.Mask")
			(net 413 "unconnected-(J18-PadF10)")
			(pinfunction "F10")
			(pintype "passive+no_connect")
		)
		(pad "F11" smd circle
			(at 12.065 -0.635 90)
			(size 0.64 0.64)
			(layers "B.Cu" "B.Mask")
			(net 402 "unconnected-(J18-PadF11)")
			(pinfunction "F11")
			(pintype "passive+no_connect")
		)
		(pad "F12" smd circle
			(at 10.795 -0.635 90)
			(size 0.64 0.64)
			(layers "B.Cu" "B.Mask")
			(net 1 "GND")
			(pinfunction "F12")
			(pintype "passive")
		)
		(pad "F13" smd circle
			(at 9.525 -0.635 90)
			(size 0.64 0.64)
			(layers "B.Cu" "B.Mask")
			(net 445 "unconnected-(J18-PadF13)")
			(pinfunction "F13")
			(pintype "passive+no_connect")
		)
		(pad "F14" smd circle
			(at 8.255 -0.635 90)
			(size 0.64 0.64)
			(layers "B.Cu" "B.Mask")
			(net 427 "unconnected-(J18-PadF14)")
			(pinfunction "F14")
			(pintype "passive+no_connect")
		)
		(pad "F15" smd circle
			(at 6.985 -0.635 90)
			(size 0.64 0.64)
			(layers "B.Cu" "B.Mask")
			(net 1 "GND")
			(pinfunction "F15")
			(pintype "passive")
		)
		(pad "F16" smd circle
			(at 5.715 -0.635 90)
			(size 0.64 0.64)
			(layers "B.Cu" "B.Mask")
			(net 363 "unconnected-(J18-PadF16)")
			(pinfunction "F16")
			(pintype "passive+no_connect")
		)
		(pad "F17" smd circle
			(at 4.445 -0.635 90)
			(size 0.64 0.64)
			(layers "B.Cu" "B.Mask")
			(net 474 "unconnected-(J18-PadF17)")
			(pinfunction "F17")
			(pintype "passive+no_connect")
		)
		(pad "F18" smd circle
			(at 3.175 -0.635 90)
			(size 0.64 0.64)
			(layers "B.Cu" "B.Mask")
			(net 1 "GND")
			(pinfunction "F18")
			(pintype "passive")
		)
		(pad "F19" smd circle
			(at 1.905 -0.635 90)
			(size 0.64 0.64)
			(layers "B.Cu" "B.Mask")
			(net 577 "unconnected-(J18-PadF19)")
			(pinfunction "F19")
			(pintype "passive+no_connect")
		)
		(pad "F20" smd circle
			(at 0.635 -0.635 90)
			(size 0.64 0.64)
			(layers "B.Cu" "B.Mask")
			(net 454 "unconnected-(J18-PadF20)")
			(pinfunction "F20")
			(pintype "passive+no_connect")
		)
		(pad "F21" smd circle
			(at -0.635 -0.635 90)
			(size 0.64 0.64)
			(layers "B.Cu" "B.Mask")
			(net 1 "GND")
			(pinfunction "F21")
			(pintype "passive")
		)
		(pad "F22" smd circle
			(at -1.905 -0.635 90)
			(size 0.64 0.64)
			(layers "B.Cu" "B.Mask")
			(net 658 "unconnected-(J18-PadF22)")
			(pinfunction "F22")
			(pintype "passive+no_connect")
		)
		(pad "F23" smd circle
			(at -3.175 -0.635 90)
			(size 0.64 0.64)
			(layers "B.Cu" "B.Mask")
			(net 337 "unconnected-(J18-PadF23)")
			(pinfunction "F23")
			(pintype "passive+no_connect")
		)
		(pad "F24" smd circle
			(at -4.445 -0.635 90)
			(size 0.64 0.64)
			(layers "B.Cu" "B.Mask")
			(net 1 "GND")
			(pinfunction "F24")
			(pintype "passive")
		)
		(pad "F25" smd circle
			(at -5.715 -0.635 90)
			(size 0.64 0.64)
			(layers "B.Cu" "B.Mask")
			(net 628 "unconnected-(J18-PadF25)")
			(pinfunction "F25")
			(pintype "passive+no_connect")
		)
		(pad "F26" smd circle
			(at -6.985 -0.635 90)
			(size 0.64 0.64)
			(layers "B.Cu" "B.Mask")
			(net 594 "unconnected-(J18-PadF26)")
			(pinfunction "F26")
			(pintype "passive+no_connect")
		)
		(pad "F27" smd circle
			(at -8.255 -0.635 90)
			(size 0.64 0.64)
			(layers "B.Cu" "B.Mask")
			(net 1 "GND")
			(pinfunction "F27")
			(pintype "passive")
		)
		(pad "F28" smd circle
			(at -9.525 -0.635 90)
			(size 0.64 0.64)
			(layers "B.Cu" "B.Mask")
			(net 465 "unconnected-(J18-PadF28)")
			(pinfunction "F28")
			(pintype "passive+no_connect")
		)
		(pad "F29" smd circle
			(at -10.795 -0.635 90)
			(size 0.64 0.64)
			(layers "B.Cu" "B.Mask")
			(net 745 "unconnected-(J18-PadF29)")
			(pinfunction "F29")
			(pintype "passive+no_connect")
		)
		(pad "F30" smd circle
			(at -12.065 -0.635 90)
			(size 0.64 0.64)
			(layers "B.Cu" "B.Mask")
			(net 1 "GND")
			(pinfunction "F30")
			(pintype "passive")
		)
		(pad "F31" smd circle
			(at -13.335 -0.635 90)
			(size 0.64 0.64)
			(layers "B.Cu" "B.Mask")
			(net 708 "unconnected-(J18-PadF31)")
			(pinfunction "F31")
			(pintype "passive+no_connect")
		)
		(pad "F32" smd circle
			(at -14.605 -0.635 90)
			(size 0.64 0.64)
			(layers "B.Cu" "B.Mask")
			(net 611 "unconnected-(J18-PadF32)")
			(pinfunction "F32")
			(pintype "passive+no_connect")
		)
		(pad "F33" smd circle
			(at -15.875 -0.635 90)
			(size 0.64 0.64)
			(layers "B.Cu" "B.Mask")
			(net 1 "GND")
			(pinfunction "F33")
			(pintype "passive")
		)
		(pad "F34" smd circle
			(at -17.145 -0.635 90)
			(size 0.64 0.64)
			(layers "B.Cu" "B.Mask")
			(net 403 "unconnected-(J18-PadF34)")
			(pinfunction "F34")
			(pintype "passive+no_connect")
		)
		(pad "F35" smd circle
			(at -18.415 -0.635 90)
			(size 0.64 0.64)
			(layers "B.Cu" "B.Mask")
			(net 456 "unconnected-(J18-PadF35)")
			(pinfunction "F35")
			(pintype "passive+no_connect")
		)
		(pad "F36" smd circle
			(at -19.685 -0.635 90)
			(size 0.64 0.64)
			(layers "B.Cu" "B.Mask")
			(net 1 "GND")
			(pinfunction "F36")
			(pintype "passive")
		)
		(pad "F37" smd circle
			(at -20.955 -0.635 90)
			(size 0.64 0.64)
			(layers "B.Cu" "B.Mask")
			(net 424 "unconnected-(J18-PadF37)")
			(pinfunction "F37")
			(pintype "passive+no_connect")
		)
		(pad "F38" smd circle
			(at -22.225 -0.635 90)
			(size 0.64 0.64)
			(layers "B.Cu" "B.Mask")
			(net 404 "unconnected-(J18-PadF38)")
			(pinfunction "F38")
			(pintype "passive+no_connect")
		)
		(pad "F39" smd circle
			(at -23.495 -0.635 90)
			(size 0.64 0.64)
			(layers "B.Cu" "B.Mask")
			(net 1 "GND")
			(pinfunction "F39")
			(pintype "passive")
		)
		(pad "F40" smd circle
			(at -24.765 -0.635 90)
			(size 0.64 0.64)
			(layers "B.Cu" "B.Mask")
			(net 295 "/Expansion connector/+V_{ADJ}")
			(pinfunction "F40")
			(pintype "passive")
		)
		(pad "G01" smd circle
			(at 24.765 -1.905 90)
			(size 0.64 0.64)
			(layers "B.Cu" "B.Mask")
			(net 1 "GND")
			(pinfunction "G01")
			(pintype "passive")
		)
		(pad "G02" smd circle
			(at 23.495 -1.905 90)
			(size 0.64 0.64)
			(layers "B.Cu" "B.Mask")
			(net 362 "/Expansion connector/GPIO.MCLK01")
			(pinfunction "G02")
			(pintype "passive")
		)
		(pad "G03" smd circle
			(at 22.225 -1.905 90)
			(size 0.64 0.64)
			(layers "B.Cu" "B.Mask")
			(net 416 "/Expansion connector/GPIO.MCLK02")
			(pinfunction "G03")
			(pintype "passive")
		)
		(pad "G04" smd circle
			(at 20.955 -1.905 90)
			(size 0.64 0.64)
			(layers "B.Cu" "B.Mask")
			(net 1 "GND")
			(pinfunction "G04")
			(pintype "passive")
		)
		(pad "G05" smd circle
			(at 19.685 -1.905 90)
			(size 0.64 0.64)
			(layers "B.Cu" "B.Mask")
			(net 1 "GND")
			(pinfunction "G05")
			(pintype "passive")
		)
		(pad "G06" smd circle
			(at 18.415 -1.905 90)
			(size 0.64 0.64)
			(layers "B.Cu" "B.Mask")
			(net 120 "/Expansion connector/I2S2.CLK")
			(pinfunction "G06")
			(pintype "passive")
		)
		(pad "G07" smd circle
			(at 17.145 -1.905 90)
			(size 0.64 0.64)
			(layers "B.Cu" "B.Mask")
			(net 146 "/Expansion connector/I2S2.FS")
			(pinfunction "G07")
			(pintype "passive")
		)
		(pad "G08" smd circle
			(at 15.875 -1.905 90)
			(size 0.64 0.64)
			(layers "B.Cu" "B.Mask")
			(net 1 "GND")
			(pinfunction "G08")
			(pintype "passive")
		)
		(pad "G09" smd circle
			(at 14.605 -1.905 90)
			(size 0.64 0.64)
			(layers "B.Cu" "B.Mask")
			(net 172 "/Expansion connector/I2S2.SDOUT")
			(pinfunction "G09")
			(pintype "passive")
		)
		(pad "G10" smd circle
			(at 13.335 -1.905 90)
			(size 0.64 0.64)
			(layers "B.Cu" "B.Mask")
			(net 168 "/Expansion connector/I2S2.SDIN")
			(pinfunction "G10")
			(pintype "passive")
		)
		(pad "G11" smd circle
			(at 12.065 -1.905 90)
			(size 0.64 0.64)
			(layers "B.Cu" "B.Mask")
			(net 1 "GND")
			(pinfunction "G11")
			(pintype "passive")
		)
		(pad "G12" smd circle
			(at 10.795 -1.905 90)
			(size 0.64 0.64)
			(layers "B.Cu" "B.Mask")
			(net 165 "/Expansion connector/I2S3.CLK")
			(pinfunction "G12")
			(pintype "passive")
		)
		(pad "G13" smd circle
			(at 9.525 -1.905 90)
			(size 0.64 0.64)
			(layers "B.Cu" "B.Mask")
			(net 111 "/Expansion connector/I2S3.FS")
			(pinfunction "G13")
			(pintype "passive")
		)
		(pad "G14" smd circle
			(at 8.255 -1.905 90)
			(size 0.64 0.64)
			(layers "B.Cu" "B.Mask")
			(net 1 "GND")
			(pinfunction "G14")
			(pintype "passive")
		)
		(pad "G15" smd circle
			(at 6.985 -1.905 90)
			(size 0.64 0.64)
			(layers "B.Cu" "B.Mask")
			(net 141 "/Expansion connector/I2S3.SDOUT")
			(pinfunction "G15")
			(pintype "passive")
		)
		(pad "G16" smd circle
			(at 5.715 -1.905 90)
			(size 0.64 0.64)
			(layers "B.Cu" "B.Mask")
			(net 114 "/Expansion connector/I2S3.SDIN")
			(pinfunction "G16")
			(pintype "passive")
		)
		(pad "G17" smd circle
			(at 4.445 -1.905 90)
			(size 0.64 0.64)
			(layers "B.Cu" "B.Mask")
			(net 1 "GND")
			(pinfunction "G17")
			(pintype "passive")
		)
		(pad "G18" smd circle
			(at 3.175 -1.905 90)
			(size 0.64 0.64)
			(layers "B.Cu" "B.Mask")
			(net 292 "/Expansion connector/SPI1.~{CS0}")
			(pinfunction "G18")
			(pintype "passive")
		)
		(pad "G19" smd circle
			(at 1.905 -1.905 90)
			(size 0.64 0.64)
			(layers "B.Cu" "B.Mask")
			(net 364 "/Expansion connector/SPI1.~{CS1}")
			(pinfunction "G19")
			(pintype "passive")
		)
		(pad "G20" smd circle
			(at 0.635 -1.905 90)
			(size 0.64 0.64)
			(layers "B.Cu" "B.Mask")
			(net 1 "GND")
			(pinfunction "G20")
			(pintype "passive")
		)
		(pad "G21" smd circle
			(at -0.635 -1.905 90)
			(size 0.64 0.64)
			(layers "B.Cu" "B.Mask")
			(net 69 "/Expansion connector/SPI1.MISO")
			(pinfunction "G21")
			(pintype "passive")
		)
		(pad "G22" smd circle
			(at -1.905 -1.905 90)
			(size 0.64 0.64)
			(layers "B.Cu" "B.Mask")
			(net 65 "/Expansion connector/SPI1.MOSI")
			(pinfunction "G22")
			(pintype "passive")
		)
		(pad "G23" smd circle
			(at -3.175 -1.905 90)
			(size 0.64 0.64)
			(layers "B.Cu" "B.Mask")
			(net 1 "GND")
			(pinfunction "G23")
			(pintype "passive")
		)
		(pad "G24" smd circle
			(at -4.445 -1.905 90)
			(size 0.64 0.64)
			(layers "B.Cu" "B.Mask")
			(net 421 "/Expansion connector/SPI1.SCK")
			(pinfunction "G24")
			(pintype "passive")
		)
		(pad "G25" smd circle
			(at -5.715 -1.905 90)
			(size 0.64 0.64)
			(layers "B.Cu" "B.Mask")
			(net 409 "/Expansion connector/SPI2.~{CS0}")
			(pinfunction "G25")
			(pintype "passive")
		)
		(pad "G26" smd circle
			(at -6.985 -1.905 90)
			(size 0.64 0.64)
			(layers "B.Cu" "B.Mask")
			(net 1 "GND")
			(pinfunction "G26")
			(pintype "passive")
		)
		(pad "G27" smd circle
			(at -8.255 -1.905 90)
			(size 0.64 0.64)
			(layers "B.Cu" "B.Mask")
			(net 393 "/Expansion connector/SPI2.SCK")
			(pinfunction "G27")
			(pintype "passive")
		)
		(pad "G28" smd circle
			(at -9.525 -1.905 90)
			(size 0.64 0.64)
			(layers "B.Cu" "B.Mask")
			(net 109 "/Expansion connector/SPI2.MISO")
			(pinfunction "G28")
			(pintype "passive")
		)
		(pad "G29" smd circle
			(at -10.795 -1.905 90)
			(size 0.64 0.64)
			(layers "B.Cu" "B.Mask")
			(net 1 "GND")
			(pinfunction "G29")
			(pintype "passive")
		)
		(pad "G30" smd circle
			(at -12.065 -1.905 90)
			(size 0.64 0.64)
			(layers "B.Cu" "B.Mask")
			(net 173 "/Expansion connector/SPI2.MOSI")
			(pinfunction "G30")
			(pintype "passive")
		)
		(pad "G31" smd circle
			(at -13.335 -1.905 90)
			(size 0.64 0.64)
			(layers "B.Cu" "B.Mask")
			(net 438 "/Expansion connector/SPI3.~{CS0}")
			(pinfunction "G31")
			(pintype "passive")
		)
		(pad "G32" smd circle
			(at -14.605 -1.905 90)
			(size 0.64 0.64)
			(layers "B.Cu" "B.Mask")
			(net 1 "GND")
			(pinfunction "G32")
			(pintype "passive")
		)
		(pad "G33" smd circle
			(at -15.875 -1.905 90)
			(size 0.64 0.64)
			(layers "B.Cu" "B.Mask")
			(net 390 "unconnected-(J18-PadG33)")
			(pinfunction "G33")
			(pintype "passive+no_connect")
		)
		(pad "G34" smd circle
			(at -17.145 -1.905 90)
			(size 0.64 0.64)
			(layers "B.Cu" "B.Mask")
			(net 326 "unconnected-(J18-PadG34)")
			(pinfunction "G34")
			(pintype "passive+no_connect")
		)
		(pad "G35" smd circle
			(at -18.415 -1.905 90)
			(size 0.64 0.64)
			(layers "B.Cu" "B.Mask")
			(net 1 "GND")
			(pinfunction "G35")
			(pintype "passive")
		)
	)
)
